# TIMECARD (Time Appliance Project (Time Card)) — schematic netlist excerpt (pin names and nets, part order shuffled) for the footprints in the layout excerpt that follows; sources: Cadence DE-HDL packaged netlist, KiCad conversion of R4006-B0001-02_R01.brd

C294  CAPACITOR  0.22UF 25V 10%  pkg SMC_0402R_H022  page 31 : \1\ = XP3R3V_FPGA_EN_R ; \2\ = SG
R340  RESISTOR  4.7KOHM 1%  pkg SMC_0402R_H016  page 17 : \1\ = XP3R3V_FPGA ; \2\ = FPGA_IN_LM75B_INT1_N

(kicad_pcb
	(version 20260206)
	(generator "pcbnew")
	(generator_version "10.0")
	(general
		(thickness 1.6)
		(legacy_teardrops no)
	)
	(paper "A4")
	(title_block
		(title "timecard-production-celestica-r4006 — R4006-B0001-02_R01.brd")
		(comment 1 "Time Appliance Project (Time Card) / footprints 734-735 of 1113")
	)
	(layers
		(0 "F.Cu" signal "TOP")
		(4 "In1.Cu" signal "L02_GND1")
		(6 "In2.Cu" signal "L03_SIG1")
		(8 "In3.Cu" signal "L04_GND2")
		(10 "In4.Cu" signal "L05_VCC1")
		(12 "In5.Cu" signal "L06_VCC2")
		(14 "In6.Cu" signal "L07_GND3")
		(16 "In7.Cu" signal "L08_SIG2")
		(18 "In8.Cu" signal "L09_GND4")
		(2 "B.Cu" signal "BOTTOM")
		(9 "F.Adhes" user "F.Adhesive")
		(11 "B.Adhes" user "B.Adhesive")
		(13 "F.Paste" user "Package Geometry/Pastemask Top")
		(15 "B.Paste" user "Package Geometry/Pastemask Bottom")
		(5 "F.SilkS" user "Ref Des/Silkscreen Top")
		(7 "B.SilkS" user "Ref Des/Silkscreen Bottom")
		(1 "F.Mask" user "Board Geometry/Soldermask Top")
		(3 "B.Mask" user "Board Geometry/Soldermask Bottom")
		(17 "Dwgs.User" user "User.Drawings")
		(19 "Cmts.User" user "User.Comments")
		(21 "Eco1.User" user "User.Eco1")
		(23 "Eco2.User" user "User.Eco2")
		(25 "Edge.Cuts" user "Board Geometry/Outline")
		(27 "Margin" user)
		(31 "F.CrtYd" user "Package Geometry/Place Bound Top")
		(29 "B.CrtYd" user "Package Geometry/Place Bound Bottom")
		(35 "F.Fab" user "Ref Des/Assembly Top")
		(33 "B.Fab" user "Ref Des/Assembly Bottom")
	)
	(footprint ""
		(layer "B.Cu")
		(at 115.443 -73.533 180)
		(property "Reference" "C294"
			(at 0.127 2.37363 0)
			(unlocked yes)
			(layer "B.SilkS")
			(effects
				(font
					(size 0.7874 0.5842)
					(thickness 0.1524)
				)
				(justify mirror)
			)
		)
		(property "Value" "VAL*"
			(at -0.0762 2.067306 180)
			(unlocked yes)
			(layer "B.Fab")
			(hide yes)
			(effects
				(font
					(size 0.7874 0.5842)
					(thickness 0.1524)
				)
				(justify mirror)
			)
		)
		(property "Tolerance" "TOL*"
			(at -0.0762 3.032506 180)
			(unlocked yes)
			(layer "Cmts.User")
			(hide yes)
			(effects
				(font
					(size 0.7874 0.5842)
					(thickness 0.1524)
				)
				(justify mirror)
			)
		)
		(property "User Part Number" "PARTNUM*"
			(at -0.1016 4.023106 180)
			(unlocked yes)
			(layer "Cmts.User")
			(hide yes)
			(effects
				(font
					(size 0.7874 0.5842)
					(thickness 0.1524)
				)
				(justify mirror)
			)
		)
		(property "Device Type" "CAPACITOR-G105-0B224-DK,0.22UFA"
			(at -0.0508 1.127506 180)
			(unlocked yes)
			(layer "B.Fab")
			(hide yes)
			(effects
				(font
					(size 0.7874 0.5842)
					(thickness 0.1524)
				)
				(justify mirror)
			)
		)
		(duplicate_pad_numbers_are_jumpers no)
		(fp_line
			(start 1.143 0.5588)
			(end -1.143 0.5588)
			(stroke
				(width 0.1)
				(type default)
			)
			(layer "B.SilkS")
		)
		(fp_line
			(start 1.143 -0.5588)
			(end 1.143 0.5588)
			(stroke
				(width 0.1)
				(type default)
			)
			(layer "B.SilkS")
		)
		(fp_line
			(start -1.143 0.5588)
			(end -1.143 -0.5588)
			(stroke
				(width 0.1)
				(type default)
			)
			(layer "B.SilkS")
		)
		(fp_line
			(start -1.143 -0.5588)
			(end 1.143 -0.5588)
			(stroke
				(width 0.1)
				(type default)
			)
			(layer "B.SilkS")
		)
		(fp_rect
			(start 1.143 -0.5588)
			(end -1.143 0.5588)
			(stroke
				(width 0)
				(type default)
			)
			(fill no)
			(layer "B.CrtYd")
		)
		(fp_line
			(start 0.508 0.3048)
			(end -0.508 0.3048)
			(stroke
				(width 0.1)
				(type default)
			)
			(layer "B.Fab")
		)
		(fp_line
			(start 0.508 -0.3048)
			(end 0.508 0.3048)
			(stroke
				(width 0.1)
				(type default)
			)
			(layer "B.Fab")
		)
		(fp_line
			(start -0.508 0.3048)
			(end -0.508 -0.3048)
			(stroke
				(width 0.1)
				(type default)
			)
			(layer "B.Fab")
		)
		(fp_line
			(start -0.508 -0.3048)
			(end 0.508 -0.3048)
			(stroke
				(width 0.1)
				(type default)
			)
			(layer "B.Fab")
		)
		(pad "1" smd rect
			(at 0.5334 0)
			(size 0.7112 0.6096)
			(layers "B.Cu" "B.Mask" "B.Paste")
			(net "XP3R3V_FPGA_EN_R")
		)
		(pad "2" smd rect
			(at -0.5334 0)
			(size 0.7112 0.6096)
			(layers "B.Cu" "B.Mask" "B.Paste")
			(net "SG")
		)
		(zone
			(layer "B.Cu")
			(hatch none 0.5)
			(connect_pads
				(clearance 0)
			)
			(min_thickness 0.25)
			(keepout
				(tracks allowed)
				(vias not_allowed)
				(pads allowed)
				(copperpour not_allowed)
				(footprints allowed)
			)
			(placement
				(enabled no)
				(sheetname "")
			)
			(fill
				(thermal_gap 0.5)
				(thermal_bridge_width 0.5)
				(island_removal_mode 0)
			)
			(polygon
				(pts
					(xy 115.3668 -73.2282) (xy 115.5192 -73.2282) (xy 115.5192 -73.8378) (xy 115.3668 -73.8378)
				)
			)
		)
		(zone
			(layer "B.Cu")
			(hatch none 0.5)
			(connect_pads
				(clearance 0)
			)
			(min_thickness 0.25)
			(keepout
				(tracks not_allowed)
				(vias allowed)
				(pads allowed)
				(copperpour not_allowed)
				(footprints allowed)
			)
			(placement
				(enabled no)
				(sheetname "")
			)
			(fill
				(thermal_gap 0.5)
				(thermal_bridge_width 0.5)
				(island_removal_mode 0)
			)
			(polygon
				(pts
					(xy 115.3668 -73.2282) (xy 115.5192 -73.2282) (xy 115.5192 -73.8378) (xy 115.3668 -73.8378)
				)
			)
		)
	)
	(footprint ""
		(layer "B.Cu")
		(at 18.288 -74.041)
		(property "Reference" "R340"
			(at 0 3.34137 0)
			(unlocked yes)
			(layer "B.SilkS")
			(effects
				(font
					(size 0.7874 0.5842)
					(thickness 0.1524)
				)
				(justify mirror)
			)
		)
		(property "Value" "VAL*"
			(at -0.02032 2.13233 0)
			(unlocked yes)
			(layer "B.Fab")
			(hide yes)
			(effects
				(font
					(size 0.7874 0.5842)
					(thickness 0.1524)
				)
				(justify mirror)
			)
		)
		(property "Tolerance" "TOL*"
			(at -0.044704 3.05435 0)
			(unlocked yes)
			(layer "Cmts.User")
			(hide yes)
			(effects
				(font
					(size 0.7874 0.5842)
					(thickness 0.1524)
				)
				(justify mirror)
			)
		)
		(property "User Part Number" "PARTNUM*"
			(at -0.02032 4.024884 0)
			(unlocked yes)
			(layer "Cmts.User")
			(hide yes)
			(effects
				(font
					(size 0.7874 0.5842)
					(thickness 0.1524)
				)
				(justify mirror)
			)
		)
		(property "Device Type" "RESISTOR-G155-14701-01,4.7KOHMA"
			(at -0.008382 1.210564 0)
			(unlocked yes)
			(layer "B.Fab")
			(hide yes)
			(effects
				(font
					(size 0.7874 0.5842)
					(thickness 0.1524)
				)
				(justify mirror)
			)
		)
		(duplicate_pad_numbers_are_jumpers no)
		(fp_line
			(start -1.143 -0.5588)
			(end 1.143 -0.5588)
			(stroke
				(width 0.1)
				(type default)
			)
			(layer "B.SilkS")
		)
		(fp_line
			(start -1.143 0.5588)
			(end -1.143 -0.5588)
			(stroke
				(width 0.1)
				(type default)
			)
			(layer "B.SilkS")
		)
		(fp_line
			(start 1.143 -0.5588)
			(end 1.143 0.5588)
			(stroke
				(width 0.1)
				(type default)
			)
			(layer "B.SilkS")
		)
		(fp_line
			(start 1.143 0.5588)
			(end -1.143 0.5588)
			(stroke
				(width 0.1)
				(type default)
			)
			(layer "B.SilkS")
		)
		(fp_rect
			(start 1.143 -0.5588)
			(end -1.143 0.5588)
			(stroke
				(width 0)
				(type default)
			)
			(fill no)
			(layer "B.CrtYd")
		)
		(fp_line
			(start -0.508 -0.3048)
			(end 0.508 -0.3048)
			(stroke
				(width 0.1)
				(type default)
			)
			(layer "B.Fab")
		)
		(fp_line
			(start -0.508 0.3048)
			(end -0.508 -0.3048)
			(stroke
				(width 0.1)
				(type default)
			)
			(layer "B.Fab")
		)
		(fp_line
			(start 0.508 -0.3048)
			(end 0.508 0.3048)
			(stroke
				(width 0.1)
				(type default)
			)
			(layer "B.Fab")
		)
		(fp_line
			(start 0.508 0.3048)
			(end -0.508 0.3048)
			(stroke
				(width 0.1)
				(type default)
			)
			(layer "B.Fab")
		)
		(pad "1" smd rect
			(at 0.5334 0 180)
			(size 0.7112 0.6096)
			(layers "B.Cu" "B.Mask" "B.Paste")
			(net "XP3R3V_FPGA")
		)
		(pad "2" smd rect
			(at -0.5334 0 180)
			(size 0.7112 0.6096)
			(layers "B.Cu" "B.Mask" "B.Paste")
			(net "FPGA_IN_LM75B_INT1_N")
		)
		(zone
			(layer "B.Cu")
			(hatch none 0.5)
			(connect_pads
				(clearance 0)
			)
			(min_thickness 0.25)
			(keepout
				(tracks allowed)
				(vias not_allowed)
				(pads allowed)
				(copperpour not_allowed)
				(footprints allowed)
			)
			(placement
				(enabled no)
				(sheetname "")
			)
			(fill
				(thermal_gap 0.5)
				(thermal_bridge_width 0.5)
				(island_removal_mode 0)
			)
			(polygon
				(pts
					(xy 18.3642 -74.3458) (xy 18.2118 -74.3458) (xy 18.2118 -73.7362) (xy 18.3642 -73.7362)
				)
			)
		)
	)
)
